FILE_TYPE = MULTI_PHYS_TABLE;

PART 'CONN160_10131762101LF'

{========================================================================================}
:VALUE                    | PART_TYPE | MATERIAL | PART_NUMBER    = STANDARD        | LIFECYCLE     | PART_NUMBER   | JEDEC_TYPE              | DESCRIPTION                               | MANUFTR | MANUF_PN         | RD_CMPLS_LVL | CMPLS_LVL | CLASS | DIP_SMD | FROM_PJ      | DATA                     | FP_ECN | EE_CHECK_LIST | CREATOR | CREATEDAY  | PSL | STATUS | ESD_CDM | ESD_HBM | ESD_MM | MSD  | PIN_LENGTH_LONG_PIN | PIN_LENGTH_SHORT_PIN ;
{========================================================================================}
 'CONN160_10131762-101LF' | 'THLF'    | 'IO'     | 'DFHSG0FR007'(!) = ''               | ''               | 'DFHSG0FR007' |'HSD_F160D8_P2W1-2_RDH'| 'CONN DIP HOUSING 160P 8R FR(P1.2,H25.1)' | 'BER'   | '10131762-101LF' | 'EP(V1)'     | ''        | 'IO'  | 'DIP'   | 'JG5-ALBERT' | 'BER_10131762-101LF.pdf' | ''     | ''            | ''      | '20180413' | ''  | ''     | 'NA'    | 'NA'    | 'NA'   | 'NA' | '71 MILS'           | '63 MILS'           
 'CONN160_10131762-101LF' | 'THLF'    | 'EMPTY'  | 'DFHSG0FR007'(!) = ''               | ''               | 'DFHSG0FR007' |'HSD_F160D8_P2W1-2_RDH'| 'CONN DIP HOUSING 160P 8R FR(P1.2,H25.1)' | 'BER'   | '10131762-101LF' | 'EP(V1)'     | ''        | 'IO'  | 'DIP'   | 'JG5-ALBERT' | 'BER_10131762-101LF.pdf' | ''     | ''            | ''      | '20180413' | ''  | ''     | 'NA'    | 'NA'    | 'NA'   | 'NA' | '71 MILS'           | '63 MILS'           

END_PART

END.

